# S9S_MB_2U (Grand Teton) — schematic netlist excerpt (pin names and nets, part order shuffled) for the footprints in the layout excerpt that follows; sources: Cadence DE-HDL packaged netlist, KiCad conversion of 03242023_DA0F0TMBIJ0_F0T_Motherboard_J_brd_V01_OCP.brd

PU42  RAA2213404GNPHB0  RAA2213404GNP#HB0 IC  pkg PQFN17_TH_5X4  page 276
  TMON  = PVCCFA_EHV_CPU0_BTSEN
  \fault#\  = PVCCFA_EHV_CPU0_FAULT
  LGCTRL  = PVCCFA_EHV_CPU0_NC1
  VCC  = PVCCFA_EHV_CPU0_VDD1
  GL1  = PVCCFA_EHV_CPU0_LSET1
  GND1  = GND
  SW  = SW_PVCCFA_EHV_CPU0_SW1
  VIN  = SW_P12V_PVCCINFAON_CPU0_FLT
  PHASE  = SW_PVCCFA_EHV_CPU0_BOOTR1
  BOOT  = SW_PVCCFA_EHV_CPU0_BOOT1
  PWM  = PVCCFA_EHV_CPU0_BPWM1
  NC1  = PVCCFA_EHV_CPU0_NC2
  GND2  = GND
  REFIN  = PVCCINFAON_CPU0_VREF
  IMON  = PVCCFA_EHV_CPU0_BCSP1
  GND3  = GND
  GL2  = NC

(kicad_pcb
	(version 20260206)
	(generator "pcbnew")
	(generator_version "10.0")
	(general
		(thickness 1.6)
		(legacy_teardrops no)
	)
	(paper "A4")
	(title_block
		(title "03242023_DA0F0TMBIJ0_F0T_Motherboard_J_brd_V01_OCP.brd")
		(comment 1 "Grand Teton / footprints 533-533 of 6105")
	)
	(layers
		(0 "F.Cu" signal "TOP")
		(4 "In1.Cu" signal "GND")
		(6 "In2.Cu" signal "IN1")
		(8 "In3.Cu" signal "GND1")
		(10 "In4.Cu" signal "IN2")
		(12 "In5.Cu" signal "GND2")
		(14 "In6.Cu" signal "IN3")
		(16 "In7.Cu" signal "GND3")
		(18 "In8.Cu" signal "VCC")
		(20 "In9.Cu" signal "VCC1")
		(22 "In10.Cu" signal "GND4")
		(24 "In11.Cu" signal "IN4")
		(26 "In12.Cu" signal "GND5")
		(28 "In13.Cu" signal "IN5")
		(30 "In14.Cu" signal "GND6")
		(32 "In15.Cu" signal "IN6")
		(34 "In16.Cu" signal "GND7")
		(2 "B.Cu" signal "BOTTOM")
		(9 "F.Adhes" user "F.Adhesive")
		(11 "B.Adhes" user "B.Adhesive")
		(13 "F.Paste" user "Package Geometry/Pastemask Top")
		(15 "B.Paste" user "Package Geometry/Pastemask Bottom")
		(5 "F.SilkS" user "Ref Des/Silkscreen Top")
		(7 "B.SilkS" user "Ref Des/Silkscreen Bottom")
		(1 "F.Mask" user "Board Geometry/Soldermask Top")
		(3 "B.Mask" user "Board Geometry/Soldermask Bottom")
		(17 "Dwgs.User" user "User.Drawings")
		(19 "Cmts.User" user "User.Comments")
		(21 "Eco1.User" user "User.Eco1")
		(23 "Eco2.User" user "User.Eco2")
		(25 "Edge.Cuts" user "Board Geometry/Outline")
		(27 "Margin" user)
		(31 "F.CrtYd" user "Package Geometry/Place Bound Top")
		(29 "B.CrtYd" user "Package Geometry/Place Bound Bottom")
		(35 "F.Fab" user "Ref Des/Assembly Top")
		(33 "B.Fab" user "Ref Des/Assembly Bottom")
	)
	(footprint ""
		(layer "F.Cu")
		(at 418.48024 -153.069036 -90)
		(property "Reference" "PU42"
			(at -0.493522 -6.4643 0)
			(unlocked yes)
			(layer "F.SilkS")
			(effects
				(font
					(size 0.7874 0.5842)
					(thickness 0.1524)
				)
				(justify left)
			)
		)
		(property "Value" ""
			(at 0 0 270)
			(layer "F.Fab")
			(effects
				(font
					(size 1.27 1.27)
				)
			)
		)
		(duplicate_pad_numbers_are_jumpers no)
		(fp_line
			(start -2.050034 2.549906)
			(end -1.27 2.549906)
			(stroke
				(width 0.1524)
				(type default)
			)
			(layer "F.SilkS")
		)
		(fp_line
			(start 1.27 2.549906)
			(end 2.050034 2.549906)
			(stroke
				(width 0.1524)
				(type default)
			)
			(layer "F.SilkS")
		)
		(fp_line
			(start 2.050034 2.549906)
			(end 2.050034 1.88976)
			(stroke
				(width 0.1524)
				(type default)
			)
			(layer "F.SilkS")
		)
		(fp_line
			(start -2.050034 1.88976)
			(end -2.050034 2.549906)
			(stroke
				(width 0.1524)
				(type default)
			)
			(layer "F.SilkS")
		)
		(fp_line
			(start -2.050034 0.406654)
			(end -2.050034 0.786384)
			(stroke
				(width 0.1524)
				(type default)
			)
			(layer "F.SilkS")
		)
		(fp_line
			(start 2.050034 0.08636)
			(end 2.050034 -0.178308)
			(stroke
				(width 0.1524)
				(type default)
			)
			(layer "F.SilkS")
		)
		(fp_line
			(start 2.050034 -1.981708)
			(end 2.050034 -2.549906)
			(stroke
				(width 0.1524)
				(type default)
			)
			(layer "F.SilkS")
		)
		(fp_line
			(start -2.050034 -2.549906)
			(end -2.050034 -2.126742)
			(stroke
				(width 0.1524)
				(type default)
			)
			(layer "F.SilkS")
		)
		(fp_line
			(start -1.61671 -2.549906)
			(end -2.050034 -2.549906)
			(stroke
				(width 0.1524)
				(type default)
			)
			(layer "F.SilkS")
		)
		(fp_line
			(start 2.050034 -2.549906)
			(end 1.916684 -2.549906)
			(stroke
				(width 0.1524)
				(type default)
			)
			(layer "F.SilkS")
		)
		(fp_poly
			(pts
				(xy -2.69621 -2.060194) (xy -2.316988 -1.87071) (xy -2.69621 -1.680972)
			)
			(stroke
				(width 0)
				(type default)
			)
			(fill yes)
			(layer "F.SilkS")
		)
		(fp_line
			(start -2.050034 2.549906)
			(end 2.050034 2.549906)
			(stroke
				(width 0.1)
				(type default)
			)
			(layer "F.Fab")
		)
		(fp_line
			(start 2.050034 2.549906)
			(end 2.050034 -2.549906)
			(stroke
				(width 0.1)
				(type default)
			)
			(layer "F.Fab")
		)
		(fp_line
			(start -2.050034 -2.549906)
			(end -2.050034 2.549906)
			(stroke
				(width 0.1)
				(type default)
			)
			(layer "F.Fab")
		)
		(fp_line
			(start 2.050034 -2.549906)
			(end -2.050034 -2.549906)
			(stroke
				(width 0.1)
				(type default)
			)
			(layer "F.Fab")
		)
		(fp_poly
			(pts
				(xy -3.43789 -2.368042) (xy -3.43789 -1.352042) (xy -2.42189 -1.860042)
			)
			(stroke
				(width 0)
				(type default)
			)
			(fill yes)
			(layer "F.Fab")
		)
		(pad "1" smd rect
			(at -1.925066 -1.860042 180)
			(size 0.254 0.5588)
			(layers "F.Cu" "F.Mask" "F.Paste")
			(net "PVCCFA_EHV_CPU0_BTSEN")
		)
		(pad "2" smd rect
			(at -1.925066 -1.359916 180)
			(size 0.254 0.5588)
			(layers "F.Cu" "F.Mask" "F.Paste")
			(net "PVCCFA_EHV_CPU0_FAULT")
		)
		(pad "3" smd rect
			(at -1.925066 -0.860044 180)
			(size 0.254 0.5588)
			(layers "F.Cu" "F.Mask" "F.Paste")
			(net "PVCCFA_EHV_CPU0_NC1")
		)
		(pad "4" smd rect
			(at -1.925066 -0.359918 180)
			(size 0.254 0.5588)
			(layers "F.Cu" "F.Mask" "F.Paste")
			(net "PVCCFA_EHV_CPU0_VDD1")
		)
		(pad "5" smd rect
			(at -1.925066 0.139954 180)
			(size 0.254 0.5588)
			(layers "F.Cu" "F.Mask" "F.Paste")
			(net "PVCCFA_EHV_CPU0_LSET1")
		)
		(pad "6_7-13_15-29" smd circle
			(at 0 0.98806)
			(size 0 0)
			(layers "F.Cu" "F.Mask" "F.Paste")
			(net "GND")
		)
		(pad "8_12" smd rect
			(at 0 2.400046 180)
			(size 0.6096 2.2606)
			(layers "F.Cu" "F.Mask" "F.Paste")
			(net "SW_PVCCFA_EHV_CPU0_SW1")
		)
		(pad "16_18-28" smd rect
			(at 1.480566 -1.080008 270)
			(size 1.4478 1.524)
			(layers "F.Cu" "F.Mask" "F.Paste")
			(net "SW_P12V_PVCCINFAON_CPU0_FLT")
		)
		(pad "19" smd rect
			(at 1.649984 -2.424938 270)
			(size 0.254 0.5588)
			(layers "F.Cu" "F.Mask" "F.Paste")
			(net "SW_PVCCFA_EHV_CPU0_BOOTR1")
		)
		(pad "20" smd rect
			(at 1.150112 -2.424938 270)
			(size 0.254 0.5588)
			(layers "F.Cu" "F.Mask" "F.Paste")
			(net "SW_PVCCFA_EHV_CPU0_BOOT1")
		)
		(pad "21" smd rect
			(at 0.649986 -2.424938 270)
			(size 0.254 0.5588)
			(layers "F.Cu" "F.Mask" "F.Paste")
			(net "PVCCFA_EHV_CPU0_BPWM1")
		)
		(pad "22" smd rect
			(at 0.150114 -2.424938 270)
			(size 0.254 0.5588)
			(layers "F.Cu" "F.Mask" "F.Paste")
			(net "PVCCFA_EHV_CPU0_NC2")
		)
		(pad "23" smd rect
			(at -0.350012 -2.424938 270)
			(size 0.254 0.5588)
			(layers "F.Cu" "F.Mask" "F.Paste")
			(net "GND")
		)
		(pad "24" smd rect
			(at -0.849884 -2.424938 270)
			(size 0.254 0.5588)
			(layers "F.Cu" "F.Mask" "F.Paste")
			(net "PVCCINFAON_CPU0_VREF")
		)
		(pad "25" smd rect
			(at -1.35001 -2.424938 270)
			(size 0.254 0.5588)
			(layers "F.Cu" "F.Mask" "F.Paste")
			(net "PVCCFA_EHV_CPU0_BCSP1")
		)
		(pad "26" smd circle
			(at -0.490728 -1.009396)
			(size 0 0)
			(layers "F.Cu" "F.Mask" "F.Paste")
			(net "GND")
		)
		(pad "27" smd rect
			(at -1.124966 0.425958 180)
			(size 0.2032 0.3556)
			(layers "F.Cu" "F.Mask" "F.Paste")
			(net "Net_8494")
		)
		(zone
			(layer "F.Cu")
			(hatch none 0.5)
			(connect_pads
				(clearance 0)
			)
			(min_thickness 0.25)
			(keepout
				(tracks not_allowed)
				(vias allowed)
				(pads allowed)
				(copperpour not_allowed)
				(footprints allowed)
			)
			(placement
				(enabled no)
				(sheetname "")
			)
			(fill
				(thermal_gap 0.5)
				(thermal_bridge_width 0.5)
				(island_removal_mode 0)
			)
			(polygon
				(pts
					(xy 416.41014 -155.11907) (xy 416.67938 -155.11907) (xy 416.67938 -151.019002) (xy 416.4203 -151.019002)
					(xy 416.4203 -151.887936) (xy 416.435794 -151.887936) (xy 416.435794 -154.250136) (xy 416.41014 -154.250136)
				)
			)
		)
		(zone
			(layer "F.Cu")
			(hatch none 0.5)
			(connect_pads
				(clearance 0)
			)
			(min_thickness 0.25)
			(keepout
				(tracks not_allowed)
				(vias allowed)
				(pads allowed)
				(copperpour not_allowed)
				(footprints allowed)
			)
			(placement
				(enabled no)
				(sheetname "")
			)
			(fill
				(thermal_gap 0.5)
				(thermal_bridge_width 0.5)
				(island_removal_mode 0)
			)
			(polygon
				(pts
					(xy 420.10584 -154.663902) (xy 420.574978 -154.663902) (xy 420.574978 -151.019002) (xy 420.373048 -151.019002)
					(xy 420.373048 -152.36317) (xy 418.747448 -152.36317) (xy 418.747448 -151.019002) (xy 418.30498 -151.019002)
					(xy 418.30498 -152.499568) (xy 418.58946 -152.499568) (xy 418.58946 -152.632156) (xy 420.398448 -152.632156)
					(xy 420.398448 -154.257756) (xy 420.168832 -154.487372) (xy 420.10584 -154.487372)
				)
			)
		)
	)
)
